(kicad_pcb
	(version 20260206)
	(generator "pcbnew")
	(generator_version "10.0")
	(general
		(thickness 1.6)
		(legacy_teardrops no)
	)
	(paper "A4")
	(title_block
		(title "04192023_DAF0TMB3IC0_F0TG_MB_C_brd_V02_OCP.brd")
		(comment 1 "Grand Teton / footprints 3786-3790 of 8354")
	)
	(layers
		(0 "F.Cu" signal "TOP")
		(4 "In1.Cu" signal "GND")
		(6 "In2.Cu" signal "IN1")
		(8 "In3.Cu" signal "GND1")
		(10 "In4.Cu" signal "IN2")
		(12 "In5.Cu" signal "GND2")
		(14 "In6.Cu" signal "IN3")
		(16 "In7.Cu" signal "GND3")
		(18 "In8.Cu" signal "VCC")
		(20 "In9.Cu" signal "VCC1")
		(22 "In10.Cu" signal "GND4")
		(24 "In11.Cu" signal "IN4")
		(26 "In12.Cu" signal "GND5")
		(28 "In13.Cu" signal "IN5")
		(30 "In14.Cu" signal "GND6")
		(32 "In15.Cu" signal "IN6")
		(34 "In16.Cu" signal "GND7")
		(2 "B.Cu" signal "BOTTOM")
		(9 "F.Adhes" user "F.Adhesive")
		(11 "B.Adhes" user "B.Adhesive")
		(13 "F.Paste" user "Package Geometry/Pastemask Top")
		(15 "B.Paste" user "Package Geometry/Pastemask Bottom")
		(5 "F.SilkS" user "Ref Des/Silkscreen Top")
		(7 "B.SilkS" user "Ref Des/Silkscreen Bottom")
		(1 "F.Mask" user "Board Geometry/Soldermask Top")
		(3 "B.Mask" user "Board Geometry/Soldermask Bottom")
		(17 "Dwgs.User" user "User.Drawings")
		(19 "Cmts.User" user "User.Comments")
		(21 "Eco1.User" user "User.Eco1")
		(23 "Eco2.User" user "User.Eco2")
		(25 "Edge.Cuts" user "Board Geometry/Outline")
		(27 "Margin" user)
		(31 "F.CrtYd" user "Package Geometry/Place Bound Top")
		(29 "B.CrtYd" user "Package Geometry/Place Bound Bottom")
		(35 "F.Fab" user "Ref Des/Assembly Top")
		(33 "B.Fab" user "Ref Des/Assembly Bottom")
	)
	(footprint ""
		(layer "F.Cu")
		(at 305.197002 -119.475504)
		(property "Reference" "R721"
			(at 0 0 0)
			(layer "F.SilkS")
			(hide yes)
			(effects
				(font
					(size 1.27 1.27)
				)
			)
		)
		(property "Value" ""
			(at 0 0 0)
			(layer "F.Fab")
			(effects
				(font
					(size 1.27 1.27)
				)
			)
		)
		(duplicate_pad_numbers_are_jumpers no)
		(fp_line
			(start -0.7874 -0.4064)
			(end 0.7874 -0.4064)
			(stroke
				(width 0.1524)
				(type default)
			)
			(layer "F.SilkS")
		)
		(fp_line
			(start -0.7874 0.4064)
			(end -0.7874 -0.4064)
			(stroke
				(width 0.1524)
				(type default)
			)
			(layer "F.SilkS")
		)
		(fp_line
			(start 0.7874 -0.4064)
			(end 0.7874 0.4064)
			(stroke
				(width 0.1524)
				(type default)
			)
			(layer "F.SilkS")
		)
		(fp_line
			(start 0.7874 0.4064)
			(end -0.7874 0.4064)
			(stroke
				(width 0.1524)
				(type default)
			)
			(layer "F.SilkS")
		)
		(fp_line
			(start -0.67945 -0.305054)
			(end -0.12065 -0.305054)
			(stroke
				(width 0.1)
				(type default)
			)
			(layer "F.Fab")
		)
		(fp_line
			(start -0.67945 0.3048)
			(end -0.67945 -0.305054)
			(stroke
				(width 0.1)
				(type default)
			)
			(layer "F.Fab")
		)
		(fp_line
			(start -0.12065 -0.305054)
			(end -0.12065 -0.2794)
			(stroke
				(width 0.1)
				(type default)
			)
			(layer "F.Fab")
		)
		(fp_line
			(start -0.12065 -0.2794)
			(end 0.12065 -0.2794)
			(stroke
				(width 0.1)
				(type default)
			)
			(layer "F.Fab")
		)
		(fp_line
			(start -0.12065 0.2794)
			(end -0.12065 0.3048)
			(stroke
				(width 0.1)
				(type default)
			)
			(layer "F.Fab")
		)
		(fp_line
			(start -0.12065 0.3048)
			(end -0.67945 0.3048)
			(stroke
				(width 0.1)
				(type default)
			)
			(layer "F.Fab")
		)
		(fp_line
			(start 0.120396 0.2794)
			(end -0.12065 0.2794)
			(stroke
				(width 0.1)
				(type default)
			)
			(layer "F.Fab")
		)
		(fp_line
			(start 0.120396 0.3048)
			(end 0.120396 0.2794)
			(stroke
				(width 0.1)
				(type default)
			)
			(layer "F.Fab")
		)
		(fp_line
			(start 0.12065 -0.3048)
			(end 0.67945 -0.3048)
			(stroke
				(width 0.1)
				(type default)
			)
			(layer "F.Fab")
		)
		(fp_line
			(start 0.12065 -0.2794)
			(end 0.12065 -0.3048)
			(stroke
				(width 0.1)
				(type default)
			)
			(layer "F.Fab")
		)
		(fp_line
			(start 0.67945 -0.3048)
			(end 0.67945 0.3048)
			(stroke
				(width 0.1)
				(type default)
			)
			(layer "F.Fab")
		)
		(fp_line
			(start 0.67945 0.3048)
			(end 0.120396 0.3048)
			(stroke
				(width 0.1)
				(type default)
			)
			(layer "F.Fab")
		)
		(pad "1" smd circle
			(at -0.40005 0)
			(size 0 0)
			(layers "F.Cu" "F.Mask" "F.Paste")
			(net "P3V3_AUX")
		)
		(pad "2" smd circle
			(at 0.40005 0)
			(size 0 0)
			(layers "F.Cu" "F.Mask" "F.Paste")
			(net "MB_FRU_ADDR0")
		)
	)
	(footprint ""
		(layer "F.Cu")
		(at 197.269608 -108.545376 180)
		(property "Reference" "R279"
			(at 0 0 180)
			(layer "F.SilkS")
			(hide yes)
			(effects
				(font
					(size 1.27 1.27)
				)
			)
		)
		(property "Value" ""
			(at 0 0 180)
			(layer "F.Fab")
			(effects
				(font
					(size 1.27 1.27)
				)
			)
		)
		(duplicate_pad_numbers_are_jumpers no)
		(fp_line
			(start 0.7874 0.4064)
			(end -0.7874 0.4064)
			(stroke
				(width 0.1524)
				(type default)
			)
			(layer "F.SilkS")
		)
		(fp_line
			(start 0.7874 -0.4064)
			(end 0.7874 0.4064)
			(stroke
				(width 0.1524)
				(type default)
			)
			(layer "F.SilkS")
		)
		(fp_line
			(start -0.7874 0.4064)
			(end -0.7874 -0.4064)
			(stroke
				(width 0.1524)
				(type default)
			)
			(layer "F.SilkS")
		)
		(fp_line
			(start -0.7874 -0.4064)
			(end 0.7874 -0.4064)
			(stroke
				(width 0.1524)
				(type default)
			)
			(layer "F.SilkS")
		)
		(fp_line
			(start 0.67945 0.3048)
			(end 0.120396 0.3048)
			(stroke
				(width 0.1)
				(type default)
			)
			(layer "F.Fab")
		)
		(fp_line
			(start 0.67945 -0.3048)
			(end 0.67945 0.3048)
			(stroke
				(width 0.1)
				(type default)
			)
			(layer "F.Fab")
		)
		(fp_line
			(start 0.12065 -0.2794)
			(end 0.12065 -0.3048)
			(stroke
				(width 0.1)
				(type default)
			)
			(layer "F.Fab")
		)
		(fp_line
			(start 0.12065 -0.3048)
			(end 0.67945 -0.3048)
			(stroke
				(width 0.1)
				(type default)
			)
			(layer "F.Fab")
		)
		(fp_line
			(start 0.120396 0.3048)
			(end 0.120396 0.2794)
			(stroke
				(width 0.1)
				(type default)
			)
			(layer "F.Fab")
		)
		(fp_line
			(start 0.120396 0.2794)
			(end -0.12065 0.2794)
			(stroke
				(width 0.1)
				(type default)
			)
			(layer "F.Fab")
		)
		(fp_line
			(start -0.12065 0.3048)
			(end -0.67945 0.3048)
			(stroke
				(width 0.1)
				(type default)
			)
			(layer "F.Fab")
		)
		(fp_line
			(start -0.12065 0.2794)
			(end -0.12065 0.3048)
			(stroke
				(width 0.1)
				(type default)
			)
			(layer "F.Fab")
		)
		(fp_line
			(start -0.12065 -0.2794)
			(end 0.12065 -0.2794)
			(stroke
				(width 0.1)
				(type default)
			)
			(layer "F.Fab")
		)
		(fp_line
			(start -0.12065 -0.305054)
			(end -0.12065 -0.2794)
			(stroke
				(width 0.1)
				(type default)
			)
			(layer "F.Fab")
		)
		(fp_line
			(start -0.67945 0.3048)
			(end -0.67945 -0.305054)
			(stroke
				(width 0.1)
				(type default)
			)
			(layer "F.Fab")
		)
		(fp_line
			(start -0.67945 -0.305054)
			(end -0.12065 -0.305054)
			(stroke
				(width 0.1)
				(type default)
			)
			(layer "F.Fab")
		)
		(pad "1" smd circle
			(at -0.40005 0 180)
			(size 0 0)
			(layers "F.Cu" "F.Mask" "F.Paste")
			(net "PVDD11_S3_P1_EN")
		)
		(pad "2" smd circle
			(at 0.40005 0 180)
			(size 0 0)
			(layers "F.Cu" "F.Mask" "F.Paste")
			(net "FM_PVDD11_S3_P1_EN")
		)
	)
	(footprint ""
		(layer "F.Cu")
		(at 432.974496 -109.13745 90)
		(property "Reference" "PR5481"
			(at 0 0 90)
			(layer "F.SilkS")
			(hide yes)
			(effects
				(font
					(size 1.27 1.27)
				)
			)
		)
		(property "Value" ""
			(at 0 0 90)
			(layer "F.Fab")
			(effects
				(font
					(size 1.27 1.27)
				)
			)
		)
		(duplicate_pad_numbers_are_jumpers no)
		(fp_line
			(start 0.7874 -0.4064)
			(end 0.7874 0.4064)
			(stroke
				(width 0.1524)
				(type default)
			)
			(layer "F.SilkS")
		)
		(fp_line
			(start -0.7874 -0.4064)
			(end 0.7874 -0.4064)
			(stroke
				(width 0.1524)
				(type default)
			)
			(layer "F.SilkS")
		)
		(fp_line
			(start 0.7874 0.4064)
			(end -0.7874 0.4064)
			(stroke
				(width 0.1524)
				(type default)
			)
			(layer "F.SilkS")
		)
		(fp_line
			(start -0.7874 0.4064)
			(end -0.7874 -0.4064)
			(stroke
				(width 0.1524)
				(type default)
			)
			(layer "F.SilkS")
		)
		(fp_line
			(start -0.12065 -0.305054)
			(end -0.12065 -0.2794)
			(stroke
				(width 0.1)
				(type default)
			)
			(layer "F.Fab")
		)
		(fp_line
			(start -0.67945 -0.305054)
			(end -0.12065 -0.305054)
			(stroke
				(width 0.1)
				(type default)
			)
			(layer "F.Fab")
		)
		(fp_line
			(start 0.67945 -0.3048)
			(end 0.67945 0.3048)
			(stroke
				(width 0.1)
				(type default)
			)
			(layer "F.Fab")
		)
		(fp_line
			(start 0.12065 -0.3048)
			(end 0.67945 -0.3048)
			(stroke
				(width 0.1)
				(type default)
			)
			(layer "F.Fab")
		)
		(fp_line
			(start 0.12065 -0.2794)
			(end 0.12065 -0.3048)
			(stroke
				(width 0.1)
				(type default)
			)
			(layer "F.Fab")
		)
		(fp_line
			(start -0.12065 -0.2794)
			(end 0.12065 -0.2794)
			(stroke
				(width 0.1)
				(type default)
			)
			(layer "F.Fab")
		)
		(fp_line
			(start 0.120396 0.2794)
			(end -0.12065 0.2794)
			(stroke
				(width 0.1)
				(type default)
			)
			(layer "F.Fab")
		)
		(fp_line
			(start -0.12065 0.2794)
			(end -0.12065 0.3048)
			(stroke
				(width 0.1)
				(type default)
			)
			(layer "F.Fab")
		)
		(fp_line
			(start 0.67945 0.3048)
			(end 0.120396 0.3048)
			(stroke
				(width 0.1)
				(type default)
			)
			(layer "F.Fab")
		)
		(fp_line
			(start 0.120396 0.3048)
			(end 0.120396 0.2794)
			(stroke
				(width 0.1)
				(type default)
			)
			(layer "F.Fab")
		)
		(fp_line
			(start -0.12065 0.3048)
			(end -0.67945 0.3048)
			(stroke
				(width 0.1)
				(type default)
			)
			(layer "F.Fab")
		)
		(fp_line
			(start -0.67945 0.3048)
			(end -0.67945 -0.305054)
			(stroke
				(width 0.1)
				(type default)
			)
			(layer "F.Fab")
		)
		(pad "1" smd circle
			(at -0.40005 0 90)
			(size 0 0)
			(layers "F.Cu" "F.Mask" "F.Paste")
			(net "P3V3_OCP_SENSE_1")
		)
		(pad "2" smd circle
			(at 0.40005 0 90)
			(size 0 0)
			(layers "F.Cu" "F.Mask" "F.Paste")
			(net "GND")
		)
	)
	(footprint ""
		(layer "F.Cu")
		(at 325.9074 -364.236)
		(property "Reference" "R351"
			(at 0 0 0)
			(layer "F.SilkS")
			(hide yes)
			(effects
				(font
					(size 1.27 1.27)
				)
			)
		)
		(property "Value" ""
			(at 0 0 0)
			(layer "F.Fab")
			(effects
				(font
					(size 1.27 1.27)
				)
			)
		)
		(duplicate_pad_numbers_are_jumpers no)
		(fp_line
			(start -0.7874 -0.4064)
			(end 0.7874 -0.4064)
			(stroke
				(width 0.1524)
				(type default)
			)
			(layer "F.SilkS")
		)
		(fp_line
			(start -0.7874 0.4064)
			(end -0.7874 -0.4064)
			(stroke
				(width 0.1524)
				(type default)
			)
			(layer "F.SilkS")
		)
		(fp_line
			(start 0.7874 -0.4064)
			(end 0.7874 0.4064)
			(stroke
				(width 0.1524)
				(type default)
			)
			(layer "F.SilkS")
		)
		(fp_line
			(start 0.7874 0.4064)
			(end -0.7874 0.4064)
			(stroke
				(width 0.1524)
				(type default)
			)
			(layer "F.SilkS")
		)
		(fp_line
			(start -0.67945 -0.305054)
			(end -0.12065 -0.305054)
			(stroke
				(width 0.1)
				(type default)
			)
			(layer "F.Fab")
		)
		(fp_line
			(start -0.67945 0.3048)
			(end -0.67945 -0.305054)
			(stroke
				(width 0.1)
				(type default)
			)
			(layer "F.Fab")
		)
		(fp_line
			(start -0.12065 -0.305054)
			(end -0.12065 -0.2794)
			(stroke
				(width 0.1)
				(type default)
			)
			(layer "F.Fab")
		)
		(fp_line
			(start -0.12065 -0.2794)
			(end 0.12065 -0.2794)
			(stroke
				(width 0.1)
				(type default)
			)
			(layer "F.Fab")
		)
		(fp_line
			(start -0.12065 0.2794)
			(end -0.12065 0.3048)
			(stroke
				(width 0.1)
				(type default)
			)
			(layer "F.Fab")
		)
		(fp_line
			(start -0.12065 0.3048)
			(end -0.67945 0.3048)
			(stroke
				(width 0.1)
				(type default)
			)
			(layer "F.Fab")
		)
		(fp_line
			(start 0.120396 0.2794)
			(end -0.12065 0.2794)
			(stroke
				(width 0.1)
				(type default)
			)
			(layer "F.Fab")
		)
		(fp_line
			(start 0.120396 0.3048)
			(end 0.120396 0.2794)
			(stroke
				(width 0.1)
				(type default)
			)
			(layer "F.Fab")
		)
		(fp_line
			(start 0.12065 -0.3048)
			(end 0.67945 -0.3048)
			(stroke
				(width 0.1)
				(type default)
			)
			(layer "F.Fab")
		)
		(fp_line
			(start 0.12065 -0.2794)
			(end 0.12065 -0.3048)
			(stroke
				(width 0.1)
				(type default)
			)
			(layer "F.Fab")
		)
		(fp_line
			(start 0.67945 -0.3048)
			(end 0.67945 0.3048)
			(stroke
				(width 0.1)
				(type default)
			)
			(layer "F.Fab")
		)
		(fp_line
			(start 0.67945 0.3048)
			(end 0.120396 0.3048)
			(stroke
				(width 0.1)
				(type default)
			)
			(layer "F.Fab")
		)
		(pad "1" smd circle
			(at -0.40005 0)
			(size 0 0)
			(layers "F.Cu" "F.Mask" "F.Paste")
			(net "SMB_SCM_2_R5_SCL")
		)
		(pad "2" smd circle
			(at 0.40005 0)
			(size 0 0)
			(layers "F.Cu" "F.Mask" "F.Paste")
			(net "SMB_SCM_2_R6_SCL")
		)
	)
	(footprint ""
		(layer "F.Cu")
		(at 300.538388 0.002794 180)
		(property "Reference" "J81"
			(at -4.350766 -1.264158 90)
			(unlocked yes)
			(layer "F.SilkS")
			(effects
				(font
					(size 0.7874 0.5842)
					(thickness 0.1524)
				)
				(justify left)
			)
		)
		(property "Value" ""
			(at 0 0 180)
			(layer "F.Fab")
			(effects
				(font
					(size 1.27 1.27)
				)
			)
		)
		(duplicate_pad_numbers_are_jumpers no)
		(fp_line
			(start 1.2192 2.06756)
			(end -1.2192 2.06756)
			(stroke
				(width 0.1524)
				(type default)
			)
			(layer "F.SilkS")
		)
		(fp_line
			(start 1.2192 -2.06756)
			(end 1.2192 2.06756)
			(stroke
				(width 0.1524)
				(type default)
			)
			(layer "F.SilkS")
		)
		(fp_line
			(start -1.2192 2.06756)
			(end -1.2192 -2.06756)
			(stroke
				(width 0.1524)
				(type default)
			)
			(layer "F.SilkS")
		)
		(fp_line
			(start -1.2192 -2.06756)
			(end 1.2192 -2.06756)
			(stroke
				(width 0.1524)
				(type default)
			)
			(layer "F.SilkS")
		)
		(pad "" np_thru_hole circle
			(at -2.8829 -1.27 90)
			(size 1.0414 1.0414)
			(drill 1.0414)
			(layers "*.Cu" "*.Mask")
			(clearance 0.381)
			(thermal_gap 0.381)
		)
		(pad "" np_thru_hole circle
			(at -2.8829 1.27 90)
			(size 1.0414 1.0414)
			(drill 1.0414)
			(layers "*.Cu" "*.Mask")
			(clearance 0.381)
			(thermal_gap 0.381)
		)
		(pad "" np_thru_hole circle
			(at 3.4671 -1.27 90)
			(size 1.0414 1.0414)
			(drill 1.0414)
			(layers "*.Cu" "*.Mask")
			(clearance 0.381)
			(thermal_gap 0.381)
		)
		(pad "" np_thru_hole circle
			(at 3.4671 1.27 90)
			(size 1.0414 1.0414)
			(drill 1.0414)
			(layers "*.Cu" "*.Mask")
			(clearance 0.381)
			(thermal_gap 0.381)
		)
		(pad "1" smd rect
			(at 0.8255 -0.249936 90)
			(size 0.3048 0.508)
			(layers "F.Cu" "F.Mask" "F.Paste")
			(net "DELTA_L_85_10INCH_TOP_DN")
		)
		(pad "2" smd rect
			(at 0.8255 0.249936 90)
			(size 0.3048 0.508)
			(layers "F.Cu" "F.Mask" "F.Paste")
			(net "DELTA_L_85_10INCH_TOP_DP")
		)
		(pad "3" smd circle
			(at 0 0 180)
			(size 0 0)
			(layers "F.Cu" "F.Mask" "F.Paste")
			(net "DELTA_L_GND_1")
		)
		(zone
			(layer "F.Cu")
			(hatch none 0.5)
			(connect_pads
				(clearance 0)
			)
			(min_thickness 0.25)
			(keepout
				(tracks not_allowed)
				(vias allowed)
				(pads allowed)
				(copperpour not_allowed)
				(footprints allowed)
			)
			(placement
				(enabled no)
				(sheetname "")
			)
			(fill
				(thermal_gap 0.5)
				(thermal_bridge_width 0.5)
				(island_removal_mode 0)
			)
			(polygon
				(pts
					(xy 299.420788 0.551434) (xy 299.420788 0.45593) (xy 300.017688 0.45593) (xy 300.017688 0.04953)
					(xy 299.420788 0.04953) (xy 299.420788 -0.043942) (xy 300.017688 -0.043942) (xy 300.017688 -0.450342)
					(xy 299.420788 -0.450342) (xy 299.420788 -0.545846) (xy 300.119288 -0.545846) (xy 300.119288 0.551434)
				)
			)
		)
		(zone
			(layers "F.Cu" "B.Cu" "In1.Cu" "In2.Cu" "In3.Cu" "In4.Cu" "In5.Cu" "In6.Cu"
				"In7.Cu" "In8.Cu" "In9.Cu" "In10.Cu" "In11.Cu" "In12.Cu" "In13.Cu" "In14.Cu"
				"In15.Cu" "In16.Cu"
			)
			(hatch none 0.5)
			(connect_pads
				(clearance 0)
			)
			(min_thickness 0.25)
			(keepout
				(tracks not_allowed)
				(vias allowed)
				(pads allowed)
				(copperpour not_allowed)
				(footprints allowed)
			)
			(placement
				(enabled no)
				(sheetname "")
			)
			(fill
				(thermal_gap 0.5)
				(thermal_bridge_width 0.5)
				(island_removal_mode 0)
			)
			(polygon
				(pts
					(arc
						(start 297.998388 -1.267206)
						(mid 296.144188 -1.267206)
						(end 297.998388 -1.267206)
					)
				)
			)
		)
		(zone
			(layers "F.Cu" "B.Cu" "In1.Cu" "In2.Cu" "In3.Cu" "In4.Cu" "In5.Cu" "In6.Cu"
				"In7.Cu" "In8.Cu" "In9.Cu" "In10.Cu" "In11.Cu" "In12.Cu" "In13.Cu" "In14.Cu"
				"In15.Cu" "In16.Cu"
			)
			(hatch none 0.5)
			(connect_pads
				(clearance 0)
			)
			(min_thickness 0.25)
			(keepout
				(tracks not_allowed)
				(vias allowed)
				(pads allowed)
				(copperpour not_allowed)
				(footprints allowed)
			)
			(placement
				(enabled no)
				(sheetname "")
			)
			(fill
				(thermal_gap 0.5)
				(thermal_bridge_width 0.5)
				(island_removal_mode 0)
			)
			(polygon
				(pts
					(arc
						(start 297.998388 1.272794)
						(mid 296.144188 1.272794)
						(end 297.998388 1.272794)
					)
				)
			)
		)
		(zone
			(layers "F.Cu" "B.Cu" "In1.Cu" "In2.Cu" "In3.Cu" "In4.Cu" "In5.Cu" "In6.Cu"
				"In7.Cu" "In8.Cu" "In9.Cu" "In10.Cu" "In11.Cu" "In12.Cu" "In13.Cu" "In14.Cu"
				"In15.Cu" "In16.Cu"
			)
			(hatch none 0.5)
			(connect_pads
				(clearance 0)
			)
			(min_thickness 0.25)
			(keepout
				(tracks not_allowed)
				(vias allowed)
				(pads allowed)
				(copperpour not_allowed)
				(footprints allowed)
			)
			(placement
				(enabled no)
				(sheetname "")
			)
			(fill
				(thermal_gap 0.5)
				(thermal_bridge_width 0.5)
				(island_removal_mode 0)
			)
			(polygon
				(pts
					(arc
						(start 304.348388 -1.267206)
						(mid 302.494188 -1.267206)
						(end 304.348388 -1.267206)
					)
				)
			)
		)
		(zone
			(layers "F.Cu" "B.Cu" "In1.Cu" "In2.Cu" "In3.Cu" "In4.Cu" "In5.Cu" "In6.Cu"
				"In7.Cu" "In8.Cu" "In9.Cu" "In10.Cu" "In11.Cu" "In12.Cu" "In13.Cu" "In14.Cu"
				"In15.Cu" "In16.Cu"
			)
			(hatch none 0.5)
			(connect_pads
				(clearance 0)
			)
			(min_thickness 0.25)
			(keepout
				(tracks not_allowed)
				(vias allowed)
				(pads allowed)
				(copperpour not_allowed)
				(footprints allowed)
			)
			(placement
				(enabled no)
				(sheetname "")
			)
			(fill
				(thermal_gap 0.5)
				(thermal_bridge_width 0.5)
				(island_removal_mode 0)
			)
			(polygon
				(pts
					(arc
						(start 304.348388 1.272794)
						(mid 302.494188 1.272794)
						(end 304.348388 1.272794)
					)
				)
			)
		)
	)
)
